# SCM (Grand Teton) — schematic netlist excerpt (pin names and nets, part order shuffled) for the footprints in the layout excerpt that follows; sources: Cadence DE-HDL packaged netlist, KiCad conversion of 12092022_DA0F0TMDCD0_F0T_Management_Board_D_brd_V3_OCP.brd

R407  Q_RES  33.2 1% CHIP  pkg 0402LF  page 13 : A = FM_BMC_SUSACK_R1_N ; B = FM_BMC_SUSACK_N
R779  Q_RES  0 5% CHIP  pkg 0402LF  page 17 : A = P2V5_AUX ; B = ADCVREFEXT1

(kicad_pcb
	(version 20260206)
	(generator "pcbnew")
	(generator_version "10.0")
	(general
		(thickness 1.6)
		(legacy_teardrops no)
	)
	(paper "A4")
	(title_block
		(title "12092022_DA0F0TMDCD0_F0T_Management_Board_D_brd_V3_OCP.brd")
		(comment 1 "Grand Teton / footprints 805-806 of 1440")
	)
	(layers
		(0 "F.Cu" signal "TOP")
		(4 "In1.Cu" signal "GND")
		(6 "In2.Cu" signal "IN1")
		(8 "In3.Cu" signal "GND1")
		(10 "In4.Cu" signal "IN2")
		(12 "In5.Cu" signal "VCC")
		(14 "In6.Cu" signal "VCC1")
		(16 "In7.Cu" signal "IN3")
		(18 "In8.Cu" signal "GND2")
		(20 "In9.Cu" signal "IN4")
		(22 "In10.Cu" signal "GND3")
		(2 "B.Cu" signal "BOTTOM")
		(9 "F.Adhes" user "F.Adhesive")
		(11 "B.Adhes" user "B.Adhesive")
		(13 "F.Paste" user "Package Geometry/Pastemask Top")
		(15 "B.Paste" user "Package Geometry/Pastemask Bottom")
		(5 "F.SilkS" user "Ref Des/Silkscreen Top")
		(7 "B.SilkS" user "Ref Des/Silkscreen Bottom")
		(1 "F.Mask" user "Board Geometry/Soldermask Top")
		(3 "B.Mask" user "Board Geometry/Soldermask Bottom")
		(17 "Dwgs.User" user "User.Drawings")
		(19 "Cmts.User" user "User.Comments")
		(21 "Eco1.User" user "User.Eco1")
		(23 "Eco2.User" user "User.Eco2")
		(25 "Edge.Cuts" user "Board Geometry/Outline")
		(27 "Margin" user)
		(31 "F.CrtYd" user "Package Geometry/Place Bound Top")
		(29 "B.CrtYd" user "Package Geometry/Place Bound Bottom")
		(35 "F.Fab" user "Ref Des/Assembly Top")
		(33 "B.Fab" user "Ref Des/Assembly Bottom")
	)
	(footprint ""
		(layer "B.Cu")
		(at 54.675024 -71.820024)
		(property "Reference" "R779"
			(at 0 0 0)
			(layer "B.SilkS")
			(hide yes)
			(effects
				(font
					(size 1.27 1.27)
				)
				(justify mirror)
			)
		)
		(property "Value" ""
			(at 0 0 0)
			(layer "B.Fab")
			(effects
				(font
					(size 1.27 1.27)
				)
				(justify mirror)
			)
		)
		(duplicate_pad_numbers_are_jumpers no)
		(fp_line
			(start -0.7874 -0.4064)
			(end -0.7874 0.4064)
			(stroke
				(width 0.1524)
				(type default)
			)
			(layer "B.SilkS")
		)
		(fp_line
			(start -0.7874 0.4064)
			(end 0.7874 0.4064)
			(stroke
				(width 0.1524)
				(type default)
			)
			(layer "B.SilkS")
		)
		(fp_line
			(start 0.7874 -0.4064)
			(end -0.7874 -0.4064)
			(stroke
				(width 0.1524)
				(type default)
			)
			(layer "B.SilkS")
		)
		(fp_line
			(start 0.7874 0.4064)
			(end 0.7874 -0.4064)
			(stroke
				(width 0.1524)
				(type default)
			)
			(layer "B.SilkS")
		)
		(fp_line
			(start -0.67945 -0.3048)
			(end -0.67945 0.3048)
			(stroke
				(width 0.1)
				(type default)
			)
			(layer "B.Fab")
		)
		(fp_line
			(start -0.67945 0.3048)
			(end -0.120396 0.3048)
			(stroke
				(width 0.1)
				(type default)
			)
			(layer "B.Fab")
		)
		(fp_line
			(start -0.12065 -0.3048)
			(end -0.67945 -0.3048)
			(stroke
				(width 0.1)
				(type default)
			)
			(layer "B.Fab")
		)
		(fp_line
			(start -0.12065 -0.2794)
			(end -0.12065 -0.3048)
			(stroke
				(width 0.1)
				(type default)
			)
			(layer "B.Fab")
		)
		(fp_line
			(start -0.120396 0.2794)
			(end 0.12065 0.2794)
			(stroke
				(width 0.1)
				(type default)
			)
			(layer "B.Fab")
		)
		(fp_line
			(start -0.120396 0.3048)
			(end -0.120396 0.2794)
			(stroke
				(width 0.1)
				(type default)
			)
			(layer "B.Fab")
		)
		(fp_line
			(start 0.12065 -0.305054)
			(end 0.12065 -0.2794)
			(stroke
				(width 0.1)
				(type default)
			)
			(layer "B.Fab")
		)
		(fp_line
			(start 0.12065 -0.2794)
			(end -0.12065 -0.2794)
			(stroke
				(width 0.1)
				(type default)
			)
			(layer "B.Fab")
		)
		(fp_line
			(start 0.12065 0.2794)
			(end 0.12065 0.3048)
			(stroke
				(width 0.1)
				(type default)
			)
			(layer "B.Fab")
		)
		(fp_line
			(start 0.12065 0.3048)
			(end 0.67945 0.3048)
			(stroke
				(width 0.1)
				(type default)
			)
			(layer "B.Fab")
		)
		(fp_line
			(start 0.67945 -0.305054)
			(end 0.12065 -0.305054)
			(stroke
				(width 0.1)
				(type default)
			)
			(layer "B.Fab")
		)
		(fp_line
			(start 0.67945 0.3048)
			(end 0.67945 -0.305054)
			(stroke
				(width 0.1)
				(type default)
			)
			(layer "B.Fab")
		)
		(pad "1" smd circle
			(at 0.40005 0 180)
			(size 0 0)
			(layers "B.Cu" "B.Mask" "B.Paste")
			(net "P2V5_AUX")
		)
		(pad "2" smd circle
			(at -0.40005 0 180)
			(size 0 0)
			(layers "B.Cu" "B.Mask" "B.Paste")
			(net "ADCVREFEXT1")
		)
	)
	(footprint ""
		(layer "B.Cu")
		(at 51.816 -66.7004 90)
		(property "Reference" "R407"
			(at 0 0 90)
			(layer "B.SilkS")
			(hide yes)
			(effects
				(font
					(size 1.27 1.27)
				)
				(justify mirror)
			)
		)
		(property "Value" ""
			(at 0 0 90)
			(layer "B.Fab")
			(effects
				(font
					(size 1.27 1.27)
				)
				(justify mirror)
			)
		)
		(duplicate_pad_numbers_are_jumpers no)
		(fp_line
			(start 0.7874 -0.4064)
			(end -0.7874 -0.4064)
			(stroke
				(width 0.1524)
				(type default)
			)
			(layer "B.SilkS")
		)
		(fp_line
			(start -0.7874 -0.4064)
			(end -0.7874 0.4064)
			(stroke
				(width 0.1524)
				(type default)
			)
			(layer "B.SilkS")
		)
		(fp_line
			(start 0.7874 0.4064)
			(end 0.7874 -0.4064)
			(stroke
				(width 0.1524)
				(type default)
			)
			(layer "B.SilkS")
		)
		(fp_line
			(start -0.7874 0.4064)
			(end 0.7874 0.4064)
			(stroke
				(width 0.1524)
				(type default)
			)
			(layer "B.SilkS")
		)
		(fp_line
			(start 0.67945 -0.305054)
			(end 0.12065 -0.305054)
			(stroke
				(width 0.1)
				(type default)
			)
			(layer "B.Fab")
		)
		(fp_line
			(start 0.12065 -0.305054)
			(end 0.12065 -0.2794)
			(stroke
				(width 0.1)
				(type default)
			)
			(layer "B.Fab")
		)
		(fp_line
			(start -0.12065 -0.3048)
			(end -0.67945 -0.3048)
			(stroke
				(width 0.1)
				(type default)
			)
			(layer "B.Fab")
		)
		(fp_line
			(start -0.67945 -0.3048)
			(end -0.67945 0.3048)
			(stroke
				(width 0.1)
				(type default)
			)
			(layer "B.Fab")
		)
		(fp_line
			(start 0.12065 -0.2794)
			(end -0.12065 -0.2794)
			(stroke
				(width 0.1)
				(type default)
			)
			(layer "B.Fab")
		)
		(fp_line
			(start -0.12065 -0.2794)
			(end -0.12065 -0.3048)
			(stroke
				(width 0.1)
				(type default)
			)
			(layer "B.Fab")
		)
		(fp_line
			(start 0.12065 0.2794)
			(end 0.12065 0.3048)
			(stroke
				(width 0.1)
				(type default)
			)
			(layer "B.Fab")
		)
		(fp_line
			(start -0.120396 0.2794)
			(end 0.12065 0.2794)
			(stroke
				(width 0.1)
				(type default)
			)
			(layer "B.Fab")
		)
		(fp_line
			(start 0.67945 0.3048)
			(end 0.67945 -0.305054)
			(stroke
				(width 0.1)
				(type default)
			)
			(layer "B.Fab")
		)
		(fp_line
			(start 0.12065 0.3048)
			(end 0.67945 0.3048)
			(stroke
				(width 0.1)
				(type default)
			)
			(layer "B.Fab")
		)
		(fp_line
			(start -0.120396 0.3048)
			(end -0.120396 0.2794)
			(stroke
				(width 0.1)
				(type default)
			)
			(layer "B.Fab")
		)
		(fp_line
			(start -0.67945 0.3048)
			(end -0.120396 0.3048)
			(stroke
				(width 0.1)
				(type default)
			)
			(layer "B.Fab")
		)
		(pad "1" smd circle
			(at 0.40005 0 270)
			(size 0 0)
			(layers "B.Cu" "B.Mask" "B.Paste")
			(net "FM_BMC_SUSACK_R1_N")
		)
		(pad "2" smd circle
			(at -0.40005 0 270)
			(size 0 0)
			(layers "B.Cu" "B.Mask" "B.Paste")
			(net "FM_BMC_SUSACK_N")
		)
	)
)
